# BASEBOARD_FAB2 (Tioga Pass) — schematic netlist excerpt (pin names and nets, part order shuffled) for the footprints in the layout excerpt that follows; sources: Cadence DE-HDL packaged netlist, KiCad conversion of Wiwynn_Tioga_Pass_MB.brd

C3N38  CAPP  470UF 2.5V 20% ALUM  pkg 3018  page 212 : A = PVCCIO_CPU0 ; B = GND
C2N6  CAP  10UF 4V 20% X6S  pkg 0603LF  page 127 : A = P1V05_PCH_STBY_KR_PLL ; B = GND
C3L12  CAP  10UF 16V 10% X6S  pkg 0805  page 236 : A = VR_FET_SW_P12V_STBY_PVDDQ_DEF ; B = GND

(kicad_pcb
	(version 20260206)
	(generator "pcbnew")
	(generator_version "10.0")
	(general
		(thickness 1.6)
		(legacy_teardrops no)
	)
	(paper "A4")
	(title_block
		(title "Wiwynn_Tioga_Pass_MB.brd")
		(comment 1 "Tioga Pass / footprints 4047-4049 of 4770")
	)
	(layers
		(0 "F.Cu" signal "TOP")
		(4 "In1.Cu" signal "L2GND")
		(6 "In2.Cu" signal "L3")
		(8 "In3.Cu" signal "L4GND")
		(10 "In4.Cu" signal "L5")
		(12 "In5.Cu" signal "L6GND")
		(14 "In6.Cu" signal "L7VCC")
		(16 "In7.Cu" signal "L8VCC")
		(18 "In8.Cu" signal "L9GND")
		(20 "In9.Cu" signal "L10")
		(22 "In10.Cu" signal "L11GND")
		(24 "In11.Cu" signal "L12")
		(26 "In12.Cu" signal "L13GND")
		(2 "B.Cu" signal "BOTTOM")
		(9 "F.Adhes" user "F.Adhesive")
		(11 "B.Adhes" user "B.Adhesive")
		(13 "F.Paste" user "Package Geometry/Pastemask Top")
		(15 "B.Paste" user "Package Geometry/Pastemask Bottom")
		(5 "F.SilkS" user "Ref Des/Silkscreen Top")
		(7 "B.SilkS" user "Ref Des/Silkscreen Bottom")
		(1 "F.Mask" user "Board Geometry/Soldermask Top")
		(3 "B.Mask" user "Board Geometry/Soldermask Bottom")
		(17 "Dwgs.User" user "User.Drawings")
		(19 "Cmts.User" user "User.Comments")
		(21 "Eco1.User" user "User.Eco1")
		(23 "Eco2.User" user "User.Eco2")
		(25 "Edge.Cuts" user "Board Geometry/Outline")
		(27 "Margin" user)
		(31 "F.CrtYd" user "Package Geometry/Place Bound Top")
		(29 "B.CrtYd" user "Package Geometry/Place Bound Bottom")
		(35 "F.Fab" user "Ref Des/Assembly Top")
		(33 "B.Fab" user "Ref Des/Assembly Bottom")
	)
	(footprint ""
		(layer "B.Cu")
		(at 401.272756 -111.636556)
		(property "Reference" "C2N6"
			(at 0 0 0)
			(layer "B.SilkS")
			(hide yes)
			(effects
				(font
					(size 1.27 1.27)
				)
				(justify mirror)
			)
		)
		(property "Value" ""
			(at 0 0 0)
			(layer "B.Fab")
			(effects
				(font
					(size 1.27 1.27)
				)
				(justify mirror)
			)
		)
		(duplicate_pad_numbers_are_jumpers no)
		(fp_poly
			(pts
				(xy 0.4953 -0.2032) (xy -0.4953 -0.2032) (xy -0.4953 1.6002) (xy 0.4953 1.6002)
			)
			(stroke
				(width 0)
				(type default)
			)
			(fill no)
			(layer "B.CrtYd")
		)
		(fp_line
			(start -0.4953 -0.2032)
			(end -0.4953 1.6002)
			(stroke
				(width 0.1)
				(type default)
			)
			(layer "B.Fab")
		)
		(fp_line
			(start -0.4953 1.6002)
			(end 0.4953 1.6002)
			(stroke
				(width 0.1)
				(type default)
			)
			(layer "B.Fab")
		)
		(fp_line
			(start 0.4953 -0.2032)
			(end -0.4953 -0.2032)
			(stroke
				(width 0.1)
				(type default)
			)
			(layer "B.Fab")
		)
		(fp_line
			(start 0.4953 1.6002)
			(end 0.4953 -0.2032)
			(stroke
				(width 0.1)
				(type default)
			)
			(layer "B.Fab")
		)
		(pad "1" smd rect
			(at 0 0 180)
			(size 0.762 0.889)
			(layers "B.Cu" "B.Mask" "B.Paste")
			(net "P1V05_PCH_STBY_KR_PLL")
		)
		(pad "2" smd rect
			(at 0 1.397 180)
			(size 0.762 0.889)
			(layers "B.Cu" "B.Mask" "B.Paste")
			(net "GND")
		)
		(zone
			(layer "B.Cu")
			(hatch none 0.5)
			(connect_pads
				(clearance 0)
			)
			(min_thickness 0.25)
			(keepout
				(tracks not_allowed)
				(vias allowed)
				(pads allowed)
				(copperpour not_allowed)
				(footprints allowed)
			)
			(placement
				(enabled no)
				(sheetname "")
			)
			(fill
				(thermal_gap 0.5)
				(thermal_bridge_width 0.5)
				(island_removal_mode 0)
			)
			(polygon
				(pts
					(xy 401.653756 -111.192056) (xy 400.891756 -111.192056) (xy 400.891756 -110.684056) (xy 401.653756 -110.684056)
				)
			)
		)
	)
	(footprint ""
		(layer "B.Cu")
		(at 336.042 -94.234 90)
		(property "Reference" "C3N38"
			(at 0.73533 -3.937 0)
			(unlocked yes)
			(layer "B.SilkS")
			(effects
				(font
					(size 0.7874 0.5842)
					(thickness 0.1524)
				)
				(justify mirror)
			)
		)
		(property "Value" ""
			(at 0 0 90)
			(layer "B.Fab")
			(effects
				(font
					(size 1.27 1.27)
				)
				(justify mirror)
			)
		)
		(duplicate_pad_numbers_are_jumpers no)
		(fp_line
			(start 2.563114 -1.616456)
			(end 2.563114 1.633728)
			(stroke
				(width 0.1524)
				(type default)
			)
			(layer "B.SilkS")
		)
		(fp_line
			(start 1.6002 -1.616456)
			(end 2.563114 -1.616456)
			(stroke
				(width 0.1524)
				(type default)
			)
			(layer "B.SilkS")
		)
		(fp_line
			(start -1.6002 -1.616456)
			(end -2.504948 -1.616456)
			(stroke
				(width 0.1524)
				(type default)
			)
			(layer "B.SilkS")
		)
		(fp_line
			(start -2.504948 -1.616456)
			(end -2.504948 1.633728)
			(stroke
				(width 0.1524)
				(type default)
			)
			(layer "B.SilkS")
		)
		(fp_line
			(start 2.563114 1.633728)
			(end 1.6002 1.633728)
			(stroke
				(width 0.1524)
				(type default)
			)
			(layer "B.SilkS")
		)
		(fp_line
			(start -2.504948 1.633728)
			(end -1.6002 1.633728)
			(stroke
				(width 0.1524)
				(type default)
			)
			(layer "B.SilkS")
		)
		(fp_line
			(start 2.286 7.366)
			(end 2.286 1.632712)
			(stroke
				(width 0.1524)
				(type default)
			)
			(layer "B.SilkS")
		)
		(fp_line
			(start 2.286 7.366)
			(end 1.60147 7.366)
			(stroke
				(width 0.1524)
				(type default)
			)
			(layer "B.SilkS")
		)
		(fp_line
			(start -2.286 7.366)
			(end -2.286 1.63195)
			(stroke
				(width 0.1524)
				(type default)
			)
			(layer "B.SilkS")
		)
		(fp_line
			(start -2.286 7.366)
			(end -1.600708 7.366)
			(stroke
				(width 0.1524)
				(type default)
			)
			(layer "B.SilkS")
		)
		(fp_rect
			(start 2.286 7.366)
			(end -2.286 -0.254)
			(stroke
				(width 0)
				(type default)
			)
			(fill no)
			(layer "B.CrtYd")
		)
		(fp_line
			(start 2.286 -0.254)
			(end -2.286 -0.254)
			(stroke
				(width 0.1)
				(type default)
			)
			(layer "B.Fab")
		)
		(fp_line
			(start -2.286 -0.254)
			(end -2.286 7.366)
			(stroke
				(width 0.1)
				(type default)
			)
			(layer "B.Fab")
		)
		(fp_line
			(start 2.286 7.366)
			(end 2.286 -0.254)
			(stroke
				(width 0.1)
				(type default)
			)
			(layer "B.Fab")
		)
		(fp_line
			(start -2.286 7.366)
			(end 2.286 7.366)
			(stroke
				(width 0.1)
				(type default)
			)
			(layer "B.Fab")
		)
		(pad "1" smd rect
			(at 0 0 270)
			(size 2.54 3.048)
			(layers "B.Cu" "B.Mask" "B.Paste")
			(net "PVCCIO_CPU0")
		)
		(pad "2" smd rect
			(at 0 7.112 270)
			(size 2.54 3.048)
			(layers "B.Cu" "B.Mask" "B.Paste")
			(net "GND")
		)
	)
	(footprint ""
		(layer "B.Cu")
		(at 375.9708 -154.457146)
		(property "Reference" "C3L12"
			(at 0 0 0)
			(layer "B.SilkS")
			(hide yes)
			(effects
				(font
					(size 1.27 1.27)
				)
				(justify mirror)
			)
		)
		(property "Value" ""
			(at 0 0 0)
			(layer "B.Fab")
			(effects
				(font
					(size 1.27 1.27)
				)
				(justify mirror)
			)
		)
		(duplicate_pad_numbers_are_jumpers no)
		(fp_poly
			(pts
				(xy 0.7239 -0.2159) (xy -0.7239 -0.2159) (xy -0.7239 1.9939) (xy 0.7239 1.9939)
			)
			(stroke
				(width 0)
				(type default)
			)
			(fill no)
			(layer "B.CrtYd")
		)
		(fp_line
			(start -0.7239 -0.2159)
			(end 0.7239 -0.2159)
			(stroke
				(width 0.1)
				(type default)
			)
			(layer "B.Fab")
		)
		(fp_line
			(start -0.7239 1.9939)
			(end -0.7239 -0.2159)
			(stroke
				(width 0.1)
				(type default)
			)
			(layer "B.Fab")
		)
		(fp_line
			(start 0.7239 -0.2159)
			(end 0.7239 1.9939)
			(stroke
				(width 0.1)
				(type default)
			)
			(layer "B.Fab")
		)
		(fp_line
			(start 0.7239 1.9939)
			(end -0.7239 1.9939)
			(stroke
				(width 0.1)
				(type default)
			)
			(layer "B.Fab")
		)
		(pad "1" smd rect
			(at 0 0 180)
			(size 1.27 1.016)
			(layers "B.Cu" "B.Mask" "B.Paste")
			(net "VR_FET_SW_P12V_STBY_PVDDQ_DEF")
		)
		(pad "2" smd rect
			(at 0 1.778 180)
			(size 1.27 1.016)
			(layers "B.Cu" "B.Mask" "B.Paste")
			(net "GND")
		)
		(zone
			(layer "B.Cu")
			(hatch none 0.5)
			(connect_pads
				(clearance 0)
			)
			(min_thickness 0.25)
			(keepout
				(tracks not_allowed)
				(vias allowed)
				(pads allowed)
				(copperpour not_allowed)
				(footprints allowed)
			)
			(placement
				(enabled no)
				(sheetname "")
			)
			(fill
				(thermal_gap 0.5)
				(thermal_bridge_width 0.5)
				(island_removal_mode 0)
			)
			(polygon
				(pts
					(xy 376.6058 -153.949146) (xy 375.3358 -153.949146) (xy 375.3358 -153.187146) (xy 376.6058 -153.187146)
				)
			)
		)
	)
)
